# T6G (Grand Teton) — schematic netlist excerpt (pin names and nets, part order shuffled) for the footprints in the layout excerpt that follows; sources: Cadence DE-HDL packaged netlist, KiCad conversion of 04192023_DAF0TMB3IC0_F0TG_MB_C_brd_V02_OCP.brd

C364  Q_CAP  220PF 50V 5% C0G  pkg C0402  page 164 : A = UART_CPU0_LVC3_UART0_RX ; B = GND
R3575  Q_RES  10 1% CHIP  pkg 0402LF  page 237 : A = P3V3_M2_0 ; B = VSENSE_P12V_INA230_4_INN

(kicad_pcb
	(version 20260206)
	(generator "pcbnew")
	(generator_version "10.0")
	(general
		(thickness 1.6)
		(legacy_teardrops no)
	)
	(paper "A4")
	(title_block
		(title "04192023_DAF0TMB3IC0_F0TG_MB_C_brd_V02_OCP.brd")
		(comment 1 "Grand Teton / footprints 4079-4080 of 8354")
	)
	(layers
		(0 "F.Cu" signal "TOP")
		(4 "In1.Cu" signal "GND")
		(6 "In2.Cu" signal "IN1")
		(8 "In3.Cu" signal "GND1")
		(10 "In4.Cu" signal "IN2")
		(12 "In5.Cu" signal "GND2")
		(14 "In6.Cu" signal "IN3")
		(16 "In7.Cu" signal "GND3")
		(18 "In8.Cu" signal "VCC")
		(20 "In9.Cu" signal "VCC1")
		(22 "In10.Cu" signal "GND4")
		(24 "In11.Cu" signal "IN4")
		(26 "In12.Cu" signal "GND5")
		(28 "In13.Cu" signal "IN5")
		(30 "In14.Cu" signal "GND6")
		(32 "In15.Cu" signal "IN6")
		(34 "In16.Cu" signal "GND7")
		(2 "B.Cu" signal "BOTTOM")
		(9 "F.Adhes" user "F.Adhesive")
		(11 "B.Adhes" user "B.Adhesive")
		(13 "F.Paste" user "Package Geometry/Pastemask Top")
		(15 "B.Paste" user "Package Geometry/Pastemask Bottom")
		(5 "F.SilkS" user "Ref Des/Silkscreen Top")
		(7 "B.SilkS" user "Ref Des/Silkscreen Bottom")
		(1 "F.Mask" user "Board Geometry/Soldermask Top")
		(3 "B.Mask" user "Board Geometry/Soldermask Bottom")
		(17 "Dwgs.User" user "User.Drawings")
		(19 "Cmts.User" user "User.Comments")
		(21 "Eco1.User" user "User.Eco1")
		(23 "Eco2.User" user "User.Eco2")
		(25 "Edge.Cuts" user "Board Geometry/Outline")
		(27 "Margin" user)
		(31 "F.CrtYd" user "Package Geometry/Place Bound Top")
		(29 "B.CrtYd" user "Package Geometry/Place Bound Bottom")
		(35 "F.Fab" user "Ref Des/Assembly Top")
		(33 "B.Fab" user "Ref Des/Assembly Bottom")
	)
	(footprint ""
		(layer "F.Cu")
		(at 364.366302 -28.2956 -90)
		(property "Reference" "C364"
			(at 0 0 270)
			(layer "F.SilkS")
			(hide yes)
			(effects
				(font
					(size 1.27 1.27)
				)
			)
		)
		(property "Value" ""
			(at 0 0 270)
			(layer "F.Fab")
			(effects
				(font
					(size 1.27 1.27)
				)
			)
		)
		(duplicate_pad_numbers_are_jumpers no)
		(fp_line
			(start -0.7874 0.4064)
			(end -0.7874 -0.4064)
			(stroke
				(width 0.1524)
				(type default)
			)
			(layer "F.SilkS")
		)
		(fp_line
			(start 0.7874 0.4064)
			(end -0.7874 0.4064)
			(stroke
				(width 0.1524)
				(type default)
			)
			(layer "F.SilkS")
		)
		(fp_line
			(start -0.7874 -0.4064)
			(end 0.7874 -0.4064)
			(stroke
				(width 0.1524)
				(type default)
			)
			(layer "F.SilkS")
		)
		(fp_line
			(start 0.7874 -0.4064)
			(end 0.7874 0.4064)
			(stroke
				(width 0.1524)
				(type default)
			)
			(layer "F.SilkS")
		)
		(fp_line
			(start -0.67945 0.3048)
			(end -0.67945 -0.305054)
			(stroke
				(width 0.1)
				(type default)
			)
			(layer "F.Fab")
		)
		(fp_line
			(start -0.12065 0.3048)
			(end -0.67945 0.3048)
			(stroke
				(width 0.1)
				(type default)
			)
			(layer "F.Fab")
		)
		(fp_line
			(start 0.120396 0.3048)
			(end 0.120396 0.2794)
			(stroke
				(width 0.1)
				(type default)
			)
			(layer "F.Fab")
		)
		(fp_line
			(start 0.67945 0.3048)
			(end 0.120396 0.3048)
			(stroke
				(width 0.1)
				(type default)
			)
			(layer "F.Fab")
		)
		(fp_line
			(start -0.12065 0.2794)
			(end -0.12065 0.3048)
			(stroke
				(width 0.1)
				(type default)
			)
			(layer "F.Fab")
		)
		(fp_line
			(start 0.120396 0.2794)
			(end -0.12065 0.2794)
			(stroke
				(width 0.1)
				(type default)
			)
			(layer "F.Fab")
		)
		(fp_line
			(start -0.12065 -0.2794)
			(end 0.12065 -0.2794)
			(stroke
				(width 0.1)
				(type default)
			)
			(layer "F.Fab")
		)
		(fp_line
			(start 0.12065 -0.2794)
			(end 0.12065 -0.3048)
			(stroke
				(width 0.1)
				(type default)
			)
			(layer "F.Fab")
		)
		(fp_line
			(start 0.12065 -0.3048)
			(end 0.67945 -0.3048)
			(stroke
				(width 0.1)
				(type default)
			)
			(layer "F.Fab")
		)
		(fp_line
			(start 0.67945 -0.3048)
			(end 0.67945 0.3048)
			(stroke
				(width 0.1)
				(type default)
			)
			(layer "F.Fab")
		)
		(fp_line
			(start -0.67945 -0.305054)
			(end -0.12065 -0.305054)
			(stroke
				(width 0.1)
				(type default)
			)
			(layer "F.Fab")
		)
		(fp_line
			(start -0.12065 -0.305054)
			(end -0.12065 -0.2794)
			(stroke
				(width 0.1)
				(type default)
			)
			(layer "F.Fab")
		)
		(pad "1" smd circle
			(at -0.40005 0 270)
			(size 0 0)
			(layers "F.Cu" "F.Mask" "F.Paste")
			(net "UART_CPU0_LVC3_UART0_RX")
		)
		(pad "2" smd circle
			(at 0.40005 0 270)
			(size 0 0)
			(layers "F.Cu" "F.Mask" "F.Paste")
			(net "GND")
		)
	)
	(footprint ""
		(layer "F.Cu")
		(at 161.571686 -57.65165 180)
		(property "Reference" "R3575"
			(at 0 0 180)
			(layer "F.SilkS")
			(hide yes)
			(effects
				(font
					(size 1.27 1.27)
				)
			)
		)
		(property "Value" ""
			(at 0 0 180)
			(layer "F.Fab")
			(effects
				(font
					(size 1.27 1.27)
				)
			)
		)
		(duplicate_pad_numbers_are_jumpers no)
		(fp_line
			(start 0.7874 0.4064)
			(end -0.7874 0.4064)
			(stroke
				(width 0.1524)
				(type default)
			)
			(layer "F.SilkS")
		)
		(fp_line
			(start 0.7874 -0.4064)
			(end 0.7874 0.4064)
			(stroke
				(width 0.1524)
				(type default)
			)
			(layer "F.SilkS")
		)
		(fp_line
			(start -0.7874 0.4064)
			(end -0.7874 -0.4064)
			(stroke
				(width 0.1524)
				(type default)
			)
			(layer "F.SilkS")
		)
		(fp_line
			(start -0.7874 -0.4064)
			(end 0.7874 -0.4064)
			(stroke
				(width 0.1524)
				(type default)
			)
			(layer "F.SilkS")
		)
		(fp_line
			(start 0.67945 0.3048)
			(end 0.120396 0.3048)
			(stroke
				(width 0.1)
				(type default)
			)
			(layer "F.Fab")
		)
		(fp_line
			(start 0.67945 -0.3048)
			(end 0.67945 0.3048)
			(stroke
				(width 0.1)
				(type default)
			)
			(layer "F.Fab")
		)
		(fp_line
			(start 0.12065 -0.2794)
			(end 0.12065 -0.3048)
			(stroke
				(width 0.1)
				(type default)
			)
			(layer "F.Fab")
		)
		(fp_line
			(start 0.12065 -0.3048)
			(end 0.67945 -0.3048)
			(stroke
				(width 0.1)
				(type default)
			)
			(layer "F.Fab")
		)
		(fp_line
			(start 0.120396 0.3048)
			(end 0.120396 0.2794)
			(stroke
				(width 0.1)
				(type default)
			)
			(layer "F.Fab")
		)
		(fp_line
			(start 0.120396 0.2794)
			(end -0.12065 0.2794)
			(stroke
				(width 0.1)
				(type default)
			)
			(layer "F.Fab")
		)
		(fp_line
			(start -0.12065 0.3048)
			(end -0.67945 0.3048)
			(stroke
				(width 0.1)
				(type default)
			)
			(layer "F.Fab")
		)
		(fp_line
			(start -0.12065 0.2794)
			(end -0.12065 0.3048)
			(stroke
				(width 0.1)
				(type default)
			)
			(layer "F.Fab")
		)
		(fp_line
			(start -0.12065 -0.2794)
			(end 0.12065 -0.2794)
			(stroke
				(width 0.1)
				(type default)
			)
			(layer "F.Fab")
		)
		(fp_line
			(start -0.12065 -0.305054)
			(end -0.12065 -0.2794)
			(stroke
				(width 0.1)
				(type default)
			)
			(layer "F.Fab")
		)
		(fp_line
			(start -0.67945 0.3048)
			(end -0.67945 -0.305054)
			(stroke
				(width 0.1)
				(type default)
			)
			(layer "F.Fab")
		)
		(fp_line
			(start -0.67945 -0.305054)
			(end -0.12065 -0.305054)
			(stroke
				(width 0.1)
				(type default)
			)
			(layer "F.Fab")
		)
		(pad "1" smd circle
			(at -0.40005 0 180)
			(size 0 0)
			(layers "F.Cu" "F.Mask" "F.Paste")
			(net "P3V3_M2_0")
		)
		(pad "2" smd circle
			(at 0.40005 0 180)
			(size 0 0)
			(layers "F.Cu" "F.Mask" "F.Paste")
			(net "VSENSE_P12V_INA230_4_INN")
		)
	)
)
